#ISCELL
  pure_quanta quanta_title_block_c *
  *
#ISCELL
  standard offpage *
  page23_i1
#ISCELL
  standard tap *
  page23_i10
#ISCELL
  standard tap *
  page23_i100
#ISCELL
  standard tap *
  page23_i101
#ISCELL
  standard tap *
  page23_i102
#ISCELL
  standard tap *
  page23_i103
#ISCELL
  standard tap *
  page23_i104
#ISCELL
  standard tap *
  page23_i105
#ISCELL
  standard tap *
  page23_i106
#ISCELL
  standard tap *
  page23_i107
#ISCELL
  standard tap *
  page23_i108
#ISCELL
  standard tap *
  page23_i109
#ISCELL
  standard tap *
  page23_i11
#ISCELL
  standard tap *
  page23_i110
#ISCELL
  standard tap *
  page23_i111
#ISCELL
  standard tap *
  page23_i112
#ISCELL
  standard tap *
  page23_i113
#ISCELL
  standard tap *
  page23_i114
#ISCELL
  standard tap *
  page23_i115
#ISCELL
  standard tap *
  page23_i116
#ISCELL
  standard tap *
  page23_i117
#ISCELL
  standard tap *
  page23_i118
#ISCELL
  standard tap *
  page23_i119
#ISCELL
  standard tap *
  page23_i12
#ISCELL
  standard tap *
  page23_i120
#ISCELL
  standard tap *
  page23_i121
#ISCELL
  standard tap *
  page23_i122
#ISCELL
  standard tap *
  page23_i123
#ISCELL
  standard tap *
  page23_i124
#ISCELL
  standard tap *
  page23_i125
#ISCELL
  standard tap *
  page23_i126
#ISCELL
  standard tap *
  page23_i127
#ISCELL
  standard tap *
  page23_i128
#ISCELL
  standard tap *
  page23_i129
#ISCELL
  standard tap *
  page23_i13
#ISCELL
  standard tap *
  page23_i130
#ISCELL
  standard tap *
  page23_i131
#ISCELL
  standard tap *
  page23_i132
#ISCELL
  standard tap *
  page23_i133
#ISCELL
  standard tap *
  page23_i134
#ISCELL
  standard tap *
  page23_i135
#ISCELL
  standard tap *
  page23_i136
#ISCELL
  standard tap *
  page23_i137
#ISCELL
  standard tap *
  page23_i138
#ISCELL
  standard tap *
  page23_i139
#ISCELL
  standard offpage *
  page23_i14
#ISCELL
  standard tap *
  page23_i140
#ISCELL
  standard tap *
  page23_i141
#ISCELL
  standard tap *
  page23_i142
#ISCELL
  standard tap *
  page23_i143
#ISCELL
  standard tap *
  page23_i144
#ISCELL
  standard tap *
  page23_i145
#ISCELL
  standard tap *
  page23_i146
#ISCELL
  standard tap *
  page23_i147
#ISCELL
  standard tap *
  page23_i148
#ISCELL
  standard tap *
  page23_i149
#ISCELL
  standard offpage *
  page23_i15
#ISCELL
  standard tap *
  page23_i150
#ISCELL
  standard tap *
  page23_i151
#ISCELL
  standard tap *
  page23_i152
#ISCELL
  standard tap *
  page23_i153
#ISCELL
  standard tap *
  page23_i154
#ISCELL
  standard tap *
  page23_i155
#ISCELL
  standard tap *
  page23_i156
#ISCELL
  standard tap *
  page23_i157
#ISCELL
  standard tap *
  page23_i158
#ISCELL
  standard offpage *
  page23_i159
#ISCELL
  standard offpage *
  page23_i16
#ISCELL
  standard offpage *
  page23_i160
#ISCELL
  standard offpage *
  page23_i161
#ISCELL
  standard offpage *
  page23_i162
#ISCELL
  standard offpage *
  page23_i163
#ISCELL
  standard offpage *
  page23_i164
#ISCELL
  standard offpage *
  page23_i165
#ISCELL
  standard offpage *
  page23_i166
#ISCELL
  standard offpage *
  page23_i167
#ISCELL
  standard offpage *
  page23_i168
#CELL
  pure_quanta socket4677_azif0045p001c01cs *
  page23_i169
#ISCELL
  standard tap *
  page23_i17
#ISCELL
  standard tap *
  page23_i18
#ISCELL
  standard tap *
  page23_i19
#ISCELL
  standard offpage *
  page23_i2
#ISCELL
  standard tap *
  page23_i20
#ISCELL
  standard tap *
  page23_i21
#ISCELL
  standard tap *
  page23_i22
#ISCELL
  standard tap *
  page23_i23
#ISCELL
  standard tap *
  page23_i24
#ISCELL
  standard tap *
  page23_i25
#ISCELL
  standard tap *
  page23_i26
#ISCELL
  standard tap *
  page23_i27
#ISCELL
  standard tap *
  page23_i28
#ISCELL
  standard tap *
  page23_i29
#ISCELL
  standard tap *
  page23_i3
#ISCELL
  standard tap *
  page23_i30
#ISCELL
  standard tap *
  page23_i31
#ISCELL
  standard tap *
  page23_i32
#ISCELL
  standard tap *
  page23_i33
#ISCELL
  standard tap *
  page23_i34
#ISCELL
  standard tap *
  page23_i35
#ISCELL
  standard tap *
  page23_i36
#ISCELL
  standard tap *
  page23_i37
#ISCELL
  standard tap *
  page23_i38
#ISCELL
  standard tap *
  page23_i39
#ISCELL
  standard tap *
  page23_i4
#ISCELL
  standard tap *
  page23_i40
#ISCELL
  standard tap *
  page23_i41
#ISCELL
  standard tap *
  page23_i42
#ISCELL
  standard tap *
  page23_i43
#ISCELL
  standard tap *
  page23_i44
#ISCELL
  standard tap *
  page23_i45
#ISCELL
  standard tap *
  page23_i46
#ISCELL
  standard tap *
  page23_i47
#ISCELL
  standard tap *
  page23_i48
#ISCELL
  standard tap *
  page23_i49
#ISCELL
  standard tap *
  page23_i5
#ISCELL
  standard tap *
  page23_i50
#ISCELL
  standard tap *
  page23_i51
#ISCELL
  standard tap *
  page23_i52
#ISCELL
  standard tap *
  page23_i53
#ISCELL
  standard tap *
  page23_i54
#ISCELL
  standard tap *
  page23_i55
#ISCELL
  standard tap *
  page23_i56
#ISCELL
  standard offpage *
  page23_i57
#ISCELL
  standard tap *
  page23_i58
#ISCELL
  standard tap *
  page23_i59
#ISCELL
  standard tap *
  page23_i6
#ISCELL
  standard tap *
  page23_i60
#ISCELL
  standard tap *
  page23_i61
#ISCELL
  standard tap *
  page23_i62
#ISCELL
  standard tap *
  page23_i63
#ISCELL
  standard tap *
  page23_i64
#ISCELL
  standard tap *
  page23_i65
#ISCELL
  standard tap *
  page23_i66
#ISCELL
  standard tap *
  page23_i67
#ISCELL
  standard tap *
  page23_i68
#ISCELL
  standard tap *
  page23_i69
#ISCELL
  standard tap *
  page23_i7
#ISCELL
  standard tap *
  page23_i70
#ISCELL
  standard tap *
  page23_i71
#ISCELL
  standard tap *
  page23_i72
#ISCELL
  standard tap *
  page23_i73
#ISCELL
  standard tap *
  page23_i74
#ISCELL
  standard tap *
  page23_i75
#ISCELL
  standard tap *
  page23_i76
#ISCELL
  standard tap *
  page23_i77
#ISCELL
  standard tap *
  page23_i78
#ISCELL
  standard tap *
  page23_i79
#ISCELL
  standard tap *
  page23_i8
#ISCELL
  standard tap *
  page23_i80
#ISCELL
  standard tap *
  page23_i81
#ISCELL
  standard tap *
  page23_i82
#ISCELL
  standard tap *
  page23_i83
#ISCELL
  standard tap *
  page23_i84
#ISCELL
  standard tap *
  page23_i85
#ISCELL
  standard tap *
  page23_i86
#ISCELL
  standard tap *
  page23_i87
#ISCELL
  standard tap *
  page23_i88
#ISCELL
  standard tap *
  page23_i89
#ISCELL
  standard tap *
  page23_i9
#ISCELL
  standard tap *
  page23_i90
#ISCELL
  standard tap *
  page23_i92
#ISCELL
  standard tap *
  page23_i93
#ISCELL
  standard tap *
  page23_i94
#ISCELL
  standard offpage *
  page23_i95
#ISCELL
  standard offpage *
  page23_i96
#ISCELL
  standard offpage *
  page23_i97
#ISCELL
  standard offpage *
  page23_i98
#ISCELL
  standard offpage *
  page23_i99
